(kicad_pcb
	(version 20241229)
	(generator "pcbnew")
	(generator_version "9.0")
	(general
		(thickness 1.62)
		(legacy_teardrops no)
	)
	(paper "A3")
	(title_block
		(title "COM Express 7 Baseboard")
		(date "2025-02-04")
		(rev "1.1.2")
		(company "Antmicro Ltd")
		(comment 1 "www.antmicro.com")
		(comment 9 "footprint 323 of 802 (J100), pads 42-71 of 71")
	)
	(layers
		(0 "F.Cu" signal)
		(4 "In1.Cu" signal)
		(6 "In2.Cu" signal)
		(8 "In3.Cu" signal)
		(10 "In4.Cu" signal)
		(12 "In5.Cu" signal)
		(14 "In6.Cu" signal)
		(2 "B.Cu" signal)
		(9 "F.Adhes" user "F.Adhesive")
		(11 "B.Adhes" user "B.Adhesive")
		(13 "F.Paste" user)
		(15 "B.Paste" user)
		(5 "F.SilkS" user "F.Silkscreen")
		(7 "B.SilkS" user "B.Silkscreen")
		(1 "F.Mask" user)
		(3 "B.Mask" user)
		(17 "Dwgs.User" user "User.Drawings")
		(19 "Cmts.User" user "User.Comments")
		(21 "Eco1.User" user "User.Eco1")
		(23 "Eco2.User" user "User.Eco2")
		(25 "Edge.Cuts" user)
		(27 "Margin" user)
		(31 "F.CrtYd" user "F.Courtyard")
		(29 "B.CrtYd" user "B.Courtyard")
		(35 "F.Fab" user)
		(33 "B.Fab" user)
	)
	(footprint "antmicro-footprints:Bus_M.2_Socket_Key_E_TE_2199230-6"
		(layer "F.Cu")
		(at 149.8245 80.3095 -90)
		(property "Reference" "J100"
			(at 12.2505 2.0245 180)
			(layer "F.SilkS")
			(effects
				(font
					(size 0.7 0.7)
					(thickness 0.15)
				)
				(justify right bottom)
			)
		)
		(property "Value" "Bus_M.2_2199230-2"
			(at -10.999 5.75 90)
			(layer "F.Fab")
			(effects
				(font
					(size 0.7 0.7)
					(thickness 0.15)
				)
				(justify right bottom)
			)
		)
		(property "Datasheet" "https://eu.mouser.com/datasheet/2/418/9/ENG_DS_1_1773702_1NGFFQRG_EN_0214_1_1773702_1NGFF_-3328593.pdf"
			(at 0 0 270)
			(layer "F.Fab")
			(hide yes)
			(effects
				(font
					(size 1.27 1.27)
					(thickness 0.15)
				)
			)
		)
		(property "Author" "Antmicro"
			(at 69.515 230.134 0)
			(layer "F.Fab")
			(hide yes)
			(effects
				(font
					(size 1 1)
					(thickness 0.15)
				)
			)
		)
		(property "License" "Apache-2.0"
			(at 69.515 230.134 0)
			(layer "F.Fab")
			(hide yes)
			(effects
				(font
					(size 1 1)
					(thickness 0.15)
				)
			)
		)
		(property "MPN" "2199230-2"
			(at 69.515 230.134 0)
			(layer "F.Fab")
			(hide yes)
			(effects
				(font
					(size 1 1)
					(thickness 0.15)
				)
			)
		)
		(property "Manufacturer" "TE Connectivity"
			(at 69.515 230.134 0)
			(layer "F.Fab")
			(hide yes)
			(effects
				(font
					(size 1 1)
					(thickness 0.15)
				)
			)
		)
		(sheetname "M.2 key E")
		(sheetfile "m2keye.kicad_sch")
		(attr smd)
		(pad "48" smd rect
			(at 2.5 3.749 270)
			(size 0.3 1.55)
			(layers "F.Cu" "F.Mask" "F.Paste")
			(net 37 "unconnected-(J100-COEX_RXD-Pad48)")
			(pinfunction "COEX_RXD")
			(pintype "bidirectional+no_connect")
			(teardrops
				(best_length_ratio 0.2)
				(max_length 1)
				(best_width_ratio 0.9)
				(max_width 2)
				(curved_edges yes)
				(filter_ratio 0.9)
				(enabled yes)
				(allow_two_segments yes)
				(prefer_zone_connections yes)
			)
		)
		(pad "49" smd rect
			(at 2.75 -3.749 270)
			(size 0.3 1.55)
			(layers "F.Cu" "F.Mask" "F.Paste")
			(net 19 "/M.2 key E/PCIE_{REF}.CK+")
			(pinfunction "REFCLK0_N")
			(pintype "input")
			(teardrops
				(best_length_ratio 0.2)
				(max_length 1)
				(best_width_ratio 0.9)
				(max_width 2)
				(curved_edges yes)
				(filter_ratio 0.9)
				(enabled yes)
				(allow_two_segments yes)
				(prefer_zone_connections yes)
			)
		)
		(pad "50" smd rect
			(at 3 3.749 270)
			(size 0.3 1.55)
			(layers "F.Cu" "F.Mask" "F.Paste")
			(net 38 "Net-(J100-SUSCLK)")
			(pinfunction "SUSCLK")
			(pintype "input")
			(teardrops
				(best_length_ratio 0.2)
				(max_length 1)
				(best_width_ratio 0.9)
				(max_width 2)
				(curved_edges yes)
				(filter_ratio 0.9)
				(enabled yes)
				(allow_two_segments yes)
				(prefer_zone_connections yes)
			)
		)
		(pad "51" smd rect
			(at 3.25 -3.749 270)
			(size 0.3 1.55)
			(layers "F.Cu" "F.Mask" "F.Paste")
			(net 1 "GND")
			(pinfunction "GND")
			(pintype "passive")
			(teardrops
				(best_length_ratio 0.2)
				(max_length 1)
				(best_width_ratio 0.9)
				(max_width 2)
				(curved_edges yes)
				(filter_ratio 0.9)
				(enabled yes)
				(allow_two_segments yes)
				(prefer_zone_connections yes)
			)
		)
		(pad "52" smd rect
			(at 3.5 3.749 270)
			(size 0.3 1.55)
			(layers "F.Cu" "F.Mask" "F.Paste")
			(net 23 "/M.2 key E/~{PERST_D}")
			(pinfunction "~{PERST0}")
			(pintype "input")
			(teardrops
				(best_length_ratio 0.2)
				(max_length 1)
				(best_width_ratio 0.9)
				(max_width 2)
				(curved_edges yes)
				(filter_ratio 0.9)
				(enabled yes)
				(allow_two_segments yes)
				(prefer_zone_connections yes)
			)
		)
		(pad "53" smd rect
			(at 3.75 -3.749 270)
			(size 0.3 1.55)
			(layers "F.Cu" "F.Mask" "F.Paste")
			(net 24 "/M.2 key E/~{CLKREQ}")
			(pinfunction "~{CLKREQ0}")
			(pintype "output")
			(teardrops
				(best_length_ratio 0.2)
				(max_length 1)
				(best_width_ratio 0.9)
				(max_width 2)
				(curved_edges yes)
				(filter_ratio 0.9)
				(enabled yes)
				(allow_two_segments yes)
				(prefer_zone_connections yes)
			)
		)
		(pad "54" smd rect
			(at 4 3.749 270)
			(size 0.3 1.55)
			(layers "F.Cu" "F.Mask" "F.Paste")
			(net 39 "unconnected-(J100-W_DISABLE2-Pad54)")
			(pinfunction "W_DISABLE2")
			(pintype "input+no_connect")
			(teardrops
				(best_length_ratio 0.2)
				(max_length 1)
				(best_width_ratio 0.9)
				(max_width 2)
				(curved_edges yes)
				(filter_ratio 0.9)
				(enabled yes)
				(allow_two_segments yes)
				(prefer_zone_connections yes)
			)
		)
		(pad "55" smd rect
			(at 4.25 -3.749 270)
			(size 0.3 1.55)
			(layers "F.Cu" "F.Mask" "F.Paste")
			(net 40 "unconnected-(J100-~{PEWAKE0}-Pad55)")
			(pinfunction "~{PEWAKE0}")
			(pintype "output+no_connect")
			(teardrops
				(best_length_ratio 0.2)
				(max_length 1)
				(best_width_ratio 0.9)
				(max_width 2)
				(curved_edges yes)
				(filter_ratio 0.9)
				(enabled yes)
				(allow_two_segments yes)
				(prefer_zone_connections yes)
			)
		)
		(pad "56" smd rect
			(at 4.5 3.749 270)
			(size 0.3 1.55)
			(layers "F.Cu" "F.Mask" "F.Paste")
			(net 900 "unconnected-(J100-W_DISABLE1-Pad56)")
			(pinfunction "W_DISABLE1")
			(pintype "input+no_connect")
			(teardrops
				(best_length_ratio 0.2)
				(max_length 1)
				(best_width_ratio 0.9)
				(max_width 2)
				(curved_edges yes)
				(filter_ratio 0.9)
				(enabled yes)
				(allow_two_segments yes)
				(prefer_zone_connections yes)
			)
		)
		(pad "57" smd rect
			(at 4.75 -3.749 270)
			(size 0.3 1.55)
			(layers "F.Cu" "F.Mask" "F.Paste")
			(net 1 "GND")
			(pinfunction "GND")
			(pintype "passive")
			(teardrops
				(best_length_ratio 0.2)
				(max_length 1)
				(best_width_ratio 0.9)
				(max_width 2)
				(curved_edges yes)
				(filter_ratio 0.9)
				(enabled yes)
				(allow_two_segments yes)
				(prefer_zone_connections yes)
			)
		)
		(pad "58" smd rect
			(at 5 3.749 270)
			(size 0.3 1.55)
			(layers "F.Cu" "F.Mask" "F.Paste")
			(net 901 "unconnected-(J100-I2C_DATA-Pad58)")
			(pinfunction "I2C_DATA")
			(pintype "bidirectional+no_connect")
			(teardrops
				(best_length_ratio 0.2)
				(max_length 1)
				(best_width_ratio 0.9)
				(max_width 2)
				(curved_edges yes)
				(filter_ratio 0.9)
				(enabled yes)
				(allow_two_segments yes)
				(prefer_zone_connections yes)
			)
		)
		(pad "59" smd rect
			(at 5.25 -3.749 270)
			(size 0.3 1.55)
			(layers "F.Cu" "F.Mask" "F.Paste")
			(net 902 "unconnected-(J100-PET1_P-Pad59)")
			(pinfunction "PET1_P")
			(pintype "input+no_connect")
			(teardrops
				(best_length_ratio 0.2)
				(max_length 1)
				(best_width_ratio 0.9)
				(max_width 2)
				(curved_edges yes)
				(filter_ratio 0.9)
				(enabled yes)
				(allow_two_segments yes)
				(prefer_zone_connections yes)
			)
		)
		(pad "60" smd rect
			(at 5.5 3.749 270)
			(size 0.3 1.55)
			(layers "F.Cu" "F.Mask" "F.Paste")
			(net 903 "unconnected-(J100-I2C_CLK-Pad60)")
			(pinfunction "I2C_CLK")
			(pintype "bidirectional+no_connect")
			(teardrops
				(best_length_ratio 0.2)
				(max_length 1)
				(best_width_ratio 0.9)
				(max_width 2)
				(curved_edges yes)
				(filter_ratio 0.9)
				(enabled yes)
				(allow_two_segments yes)
				(prefer_zone_connections yes)
			)
		)
		(pad "61" smd rect
			(at 5.75 -3.749 270)
			(size 0.3 1.55)
			(layers "F.Cu" "F.Mask" "F.Paste")
			(net 904 "unconnected-(J100-PET1_N-Pad61)")
			(pinfunction "PET1_N")
			(pintype "input+no_connect")
			(teardrops
				(best_length_ratio 0.2)
				(max_length 1)
				(best_width_ratio 0.9)
				(max_width 2)
				(curved_edges yes)
				(filter_ratio 0.9)
				(enabled yes)
				(allow_two_segments yes)
				(prefer_zone_connections yes)
			)
		)
		(pad "62" smd rect
			(at 6 3.749 270)
			(size 0.3 1.55)
			(layers "F.Cu" "F.Mask" "F.Paste")
			(net 905 "unconnected-(J100-~{ALERT}-Pad62)")
			(pinfunction "~{ALERT}")
			(pintype "output+no_connect")
			(teardrops
				(best_length_ratio 0.2)
				(max_length 1)
				(best_width_ratio 0.9)
				(max_width 2)
				(curved_edges yes)
				(filter_ratio 0.9)
				(enabled yes)
				(allow_two_segments yes)
				(prefer_zone_connections yes)
			)
		)
		(pad "63" smd rect
			(at 6.25 -3.749 270)
			(size 0.3 1.55)
			(layers "F.Cu" "F.Mask" "F.Paste")
			(net 1 "GND")
			(pinfunction "GND")
			(pintype "passive")
			(teardrops
				(best_length_ratio 0.2)
				(max_length 1)
				(best_width_ratio 0.9)
				(max_width 2)
				(curved_edges yes)
				(filter_ratio 0.9)
				(enabled yes)
				(allow_two_segments yes)
				(prefer_zone_connections yes)
			)
		)
		(pad "64" smd rect
			(at 6.5 3.749 270)
			(size 0.3 1.55)
			(layers "F.Cu" "F.Mask" "F.Paste")
			(net 906 "unconnected-(J100-RFU-Pad64)")
			(pinfunction "RFU")
			(pintype "no_connect")
			(teardrops
				(best_length_ratio 0.2)
				(max_length 1)
				(best_width_ratio 0.9)
				(max_width 2)
				(curved_edges yes)
				(filter_ratio 0.9)
				(enabled yes)
				(allow_two_segments yes)
				(prefer_zone_connections yes)
			)
		)
		(pad "65" smd rect
			(at 6.75 -3.749 270)
			(size 0.3 1.55)
			(layers "F.Cu" "F.Mask" "F.Paste")
			(net 907 "unconnected-(J100-PER1_P-Pad65)")
			(pinfunction "PER1_P")
			(pintype "output+no_connect")
			(teardrops
				(best_length_ratio 0.2)
				(max_length 1)
				(best_width_ratio 0.9)
				(max_width 2)
				(curved_edges yes)
				(filter_ratio 0.9)
				(enabled yes)
				(allow_two_segments yes)
				(prefer_zone_connections yes)
			)
		)
		(pad "66" smd rect
			(at 6.999 3.749 270)
			(size 0.3 1.55)
			(layers "F.Cu" "F.Mask" "F.Paste")
			(net 908 "unconnected-(J100-UIM_SWP-Pad66)")
			(pinfunction "UIM_SWP")
			(pintype "bidirectional+no_connect")
			(teardrops
				(best_length_ratio 0.2)
				(max_length 1)
				(best_width_ratio 0.9)
				(max_width 2)
				(curved_edges yes)
				(filter_ratio 0.9)
				(enabled yes)
				(allow_two_segments yes)
				(prefer_zone_connections yes)
			)
		)
		(pad "67" smd rect
			(at 7.249 -3.749 270)
			(size 0.3 1.55)
			(layers "F.Cu" "F.Mask" "F.Paste")
			(net 909 "unconnected-(J100-PER1_N-Pad67)")
			(pinfunction "PER1_N")
			(pintype "output+no_connect")
			(teardrops
				(best_length_ratio 0.2)
				(max_length 1)
				(best_width_ratio 0.9)
				(max_width 2)
				(curved_edges yes)
				(filter_ratio 0.9)
				(enabled yes)
				(allow_two_segments yes)
				(prefer_zone_connections yes)
			)
		)
		(pad "68" smd rect
			(at 7.499 3.749 270)
			(size 0.3 1.55)
			(layers "F.Cu" "F.Mask" "F.Paste")
			(net 910 "unconnected-(J100-UIM_POWER_SNK-Pad68)")
			(pinfunction "UIM_POWER_SNK")
			(pintype "bidirectional+no_connect")
			(teardrops
				(best_length_ratio 0.2)
				(max_length 1)
				(best_width_ratio 0.9)
				(max_width 2)
				(curved_edges yes)
				(filter_ratio 0.9)
				(enabled yes)
				(allow_two_segments yes)
				(prefer_zone_connections yes)
			)
		)
		(pad "69" smd rect
			(at 7.749 -3.749 270)
			(size 0.3 1.55)
			(layers "F.Cu" "F.Mask" "F.Paste")
			(net 1 "GND")
			(pinfunction "GND")
			(pintype "passive")
			(teardrops
				(best_length_ratio 0.2)
				(max_length 1)
				(best_width_ratio 0.9)
				(max_width 2)
				(curved_edges yes)
				(filter_ratio 0.9)
				(enabled yes)
				(allow_two_segments yes)
				(prefer_zone_connections yes)
			)
		)
		(pad "70" smd rect
			(at 7.999 3.749 270)
			(size 0.3 1.55)
			(layers "F.Cu" "F.Mask" "F.Paste")
			(net 911 "unconnected-(J100-UIM_POWER_SRC-Pad70)")
			(pinfunction "UIM_POWER_SRC")
			(pintype "bidirectional+no_connect")
			(teardrops
				(best_length_ratio 0.2)
				(max_length 1)
				(best_width_ratio 0.9)
				(max_width 2)
				(curved_edges yes)
				(filter_ratio 0.9)
				(enabled yes)
				(allow_two_segments yes)
				(prefer_zone_connections yes)
			)
		)
		(pad "71" smd rect
			(at 8.249 -3.749 270)
			(size 0.3 1.55)
			(layers "F.Cu" "F.Mask" "F.Paste")
			(net 912 "unconnected-(J100-REFCLK1_P-Pad71)")
			(pinfunction "REFCLK1_P")
			(pintype "input+no_connect")
			(teardrops
				(best_length_ratio 0.2)
				(max_length 1)
				(best_width_ratio 0.9)
				(max_width 2)
				(curved_edges yes)
				(filter_ratio 0.9)
				(enabled yes)
				(allow_two_segments yes)
				(prefer_zone_connections yes)
			)
		)
		(pad "72" smd rect
			(at 8.499 3.749 270)
			(size 0.3 1.55)
			(layers "F.Cu" "F.Mask" "F.Paste")
			(net 2 "+3V3")
			(pinfunction "3.3V")
			(pintype "passive")
			(teardrops
				(best_length_ratio 0.2)
				(max_length 1)
				(best_width_ratio 0.9)
				(max_width 2)
				(curved_edges yes)
				(filter_ratio 0.9)
				(enabled yes)
				(allow_two_segments yes)
				(prefer_zone_connections yes)
			)
		)
		(pad "73" smd rect
			(at 8.749 -3.749 270)
			(size 0.3 1.55)
			(layers "F.Cu" "F.Mask" "F.Paste")
			(net 913 "unconnected-(J100-REFCLK1_N-Pad73)")
			(pinfunction "REFCLK1_N")
			(pintype "input+no_connect")
			(teardrops
				(best_length_ratio 0.2)
				(max_length 1)
				(best_width_ratio 0.9)
				(max_width 2)
				(curved_edges yes)
				(filter_ratio 0.9)
				(enabled yes)
				(allow_two_segments yes)
				(prefer_zone_connections yes)
			)
		)
		(pad "74" smd rect
			(at 8.999 3.749 270)
			(size 0.3 1.55)
			(layers "F.Cu" "F.Mask" "F.Paste")
			(net 2 "+3V3")
			(pinfunction "3.3V")
			(pintype "passive")
			(teardrops
				(best_length_ratio 0.2)
				(max_length 1)
				(best_width_ratio 0.9)
				(max_width 2)
				(curved_edges yes)
				(filter_ratio 0.9)
				(enabled yes)
				(allow_two_segments yes)
				(prefer_zone_connections yes)
			)
		)
		(pad "75" smd rect
			(at 9.249 -3.749 270)
			(size 0.3 1.55)
			(layers "F.Cu" "F.Mask" "F.Paste")
			(net 1 "GND")
			(pinfunction "GND")
			(pintype "passive")
			(teardrops
				(best_length_ratio 0.2)
				(max_length 1)
				(best_width_ratio 0.9)
				(max_width 2)
				(curved_edges yes)
				(filter_ratio 0.9)
				(enabled yes)
				(allow_two_segments yes)
				(prefer_zone_connections yes)
			)
		)
		(pad "MP" smd rect
			(at -10.35 -3.001 270)
			(size 1.2 2.75)
			(layers "F.Cu" "F.Mask" "F.Paste")
			(net 1 "GND")
			(pinfunction "MP")
			(pintype "passive")
			(teardrops
				(best_length_ratio 0.2)
				(max_length 1)
				(best_width_ratio 0.9)
				(max_width 2)
				(curved_edges yes)
				(filter_ratio 0.9)
				(enabled yes)
				(allow_two_segments yes)
				(prefer_zone_connections yes)
			)
		)
		(pad "MP" smd rect
			(at 10.351 -3.001 270)
			(size 1.2 2.75)
			(layers "F.Cu" "F.Mask" "F.Paste")
			(net 1 "GND")
			(pinfunction "MP")
			(pintype "passive")
			(teardrops
				(best_length_ratio 0.2)
				(max_length 1)
				(best_width_ratio 0.9)
				(max_width 2)
				(curved_edges yes)
				(filter_ratio 0.9)
				(enabled yes)
				(allow_two_segments yes)
				(prefer_zone_connections yes)
			)
		)
	)
)
